FILE_TYPE = MULTI_PHYS_TABLE;

PART 'MMBT39047F'

{========================================================================================}
:VALUE          | PART_TYPE | MATERIAL | PART_NUMBER       = PART_NUMBER       | JEDEC_TYPE  | DESCRIPTION                               | MANUFTR | MANUF_PN       | RD_CMPLS_LVL | CMPLS_LVL | CLASS | DIP_SMD | FP_ECN           | FROM_PJ      | DATA                   | EE_CHECK_LIST | STANDARD        | PSL | PREFERENCE | LIFECYCLE      | CREATOR | CREATEDAY  | STATUS ;
{========================================================================================}
 'MMBT3904-7-F' | 'SMLF'    | 'IC'     | 'BA0390400H0'(!)  = 'BA0390400H0'     |'SOT23_BEC'| 'TRANS SMD MMBT3904-7-F(40V,200MA,8W)'    | 'DDS'   | 'MMBT3904-7-F' | 'EP(V1)'     | 'EP(V1)'  | 'IC'  | ''      | ''               | 'T2L-CHEESE' | 'DDS_MMBT3904-7-F.pdf' | ''            | 'End of Design' | ''  | ''         | 'Comp-Approve' | ''      | '20120131' | ''    
 'MMBT3904-7-F' | 'SMLF'    | 'EMPTY'  | 'BA0390400H0'(!)  = 'BA0390400H0'     |'SOT23_BEC'| 'TRANS SMD MMBT3904-7-F(40V,200MA,8W)'    | 'DDS'   | 'MMBT3904-7-F' | 'EP(V1)'     | 'EP(V1)'  | 'IC'  | ''      | ''               | 'T2L-CHEESE' | 'DDS_MMBT3904-7-F.pdf' | ''            | 'End of Design' | ''  | ''         | 'Comp-Approve' | ''      | '20120131' | ''    
 'MMBT3904-7-F' | 'SMLF'    | 'IC'     | 'BA0390400H0SEL1'(!) = 'BA0390400H0SEL1' |'SOT23_BEC'| 'TRANS SMD MMBT3904-7-F(40V,0.2A,8W)SELA' | 'DDS'   | 'MMBT3904-7-F' | 'EP(V1)'     | 'EP(V1)'  | 'IC'  | ''      | 'SEL_15QPN.xlsx' | 'T2L-CHEESE' | 'DDS_MMBT3904-7-F.pdf' | ''            | ''              | ''  | ''         | ''               | ''      | '20230627' | ''    
 'MMBT3904-7-F' | 'SMLF'    | 'EMPTY'  | 'BA0390400H0SEL1'(!) = 'BA0390400H0SEL1' |'SOT23_BEC'| 'TRANS SMD MMBT3904-7-F(40V,0.2A,8W)SELA' | 'DDS'   | 'MMBT3904-7-F' | 'EP(V1)'     | 'EP(V1)'  | 'IC'  | ''      | 'SEL_15QPN.xlsx' | 'T2L-CHEESE' | 'DDS_MMBT3904-7-F.pdf' | ''            | ''              | ''  | ''         | ''               | ''      | '20230627' | ''    

END_PART

END.

